(kicad_pcb
	(version 20241229)
	(generator "pcbnew")
	(generator_version "9.0")
	(general
		(thickness 1.62)
		(legacy_teardrops no)
	)
	(paper "A3")
	(title_block
		(title "COM Express 7 Baseboard")
		(date "2025-02-04")
		(rev "1.1.2")
		(company "Antmicro Ltd")
		(comment 1 "www.antmicro.com")
		(comment 9 "footprints 349-353 of 802")
	)
	(layers
		(0 "F.Cu" signal)
		(4 "In1.Cu" signal)
		(6 "In2.Cu" signal)
		(8 "In3.Cu" signal)
		(10 "In4.Cu" signal)
		(12 "In5.Cu" signal)
		(14 "In6.Cu" signal)
		(2 "B.Cu" signal)
		(9 "F.Adhes" user "F.Adhesive")
		(11 "B.Adhes" user "B.Adhesive")
		(13 "F.Paste" user)
		(15 "B.Paste" user)
		(5 "F.SilkS" user "F.Silkscreen")
		(7 "B.SilkS" user "B.Silkscreen")
		(1 "F.Mask" user)
		(3 "B.Mask" user)
		(17 "Dwgs.User" user "User.Drawings")
		(19 "Cmts.User" user "User.Comments")
		(21 "Eco1.User" user "User.Eco1")
		(23 "Eco2.User" user "User.Eco2")
		(25 "Edge.Cuts" user)
		(27 "Margin" user)
		(31 "F.CrtYd" user "F.Courtyard")
		(29 "B.CrtYd" user "B.Courtyard")
		(35 "F.Fab" user)
		(33 "B.Fab" user)
	)
	(footprint "antmicro-footprints:SW_1-1825027-1_THT"
		(layer "F.Cu")
		(at 98.398 119.71 -90)
		(descr "Tactile Switches, Round Actuator Style, NO, 5.74mm")
		(property "Reference" "SW1"
			(at 7.35 0.498 180)
			(layer "F.SilkS")
			(effects
				(font
					(size 0.7 0.7)
					(thickness 0.15)
				)
				(justify right bottom)
			)
		)
		(property "Value" "SW_1-1825027-1_THT"
			(at -2.4 9.6 90)
			(layer "F.Fab")
			(effects
				(font
					(size 0.7 0.7)
					(thickness 0.15)
				)
				(justify right bottom)
			)
		)
		(property "Datasheet" "https://www.te.com/commerce/DocumentDelivery/DDEController?Action=showdoc&DocId=Customer+Drawing%7F1825027%7FH1%7Fpdf%7FEnglish%7FENG_CD_1825027_H1.pdf%7F1-1825027-1"
			(at 0 0 270)
			(layer "F.Fab")
			(hide yes)
			(effects
				(font
					(size 1.27 1.27)
					(thickness 0.15)
				)
			)
		)
		(property "Author" "Antmicro"
			(at -21.312 218.108 0)
			(layer "F.Fab")
			(hide yes)
			(effects
				(font
					(size 1 1)
					(thickness 0.15)
				)
			)
		)
		(property "License" "Apache-2.0"
			(at -21.312 218.108 0)
			(layer "F.Fab")
			(hide yes)
			(effects
				(font
					(size 1 1)
					(thickness 0.15)
				)
			)
		)
		(property "MPN" "1-1825027-1"
			(at -21.312 218.108 0)
			(layer "F.Fab")
			(hide yes)
			(effects
				(font
					(size 1 1)
					(thickness 0.15)
				)
			)
		)
		(property "Manufacturer" "TE Connectivity"
			(at -21.312 218.108 0)
			(layer "F.Fab")
			(hide yes)
			(effects
				(font
					(size 1 1)
					(thickness 0.15)
				)
			)
		)
		(sheetname "Com Express 7 MGMT")
		(sheetfile "com_express_7_mgmt.kicad_sch")
		(attr through_hole)
		(fp_line
			(start 4.004 2.6)
			(end 0.494 2.6)
			(stroke
				(width 0.15)
				(type solid)
			)
			(layer "F.SilkS")
		)
		(fp_line
			(start -1.307 2.548)
			(end -1.307 -0.485)
			(stroke
				(width 0.15)
				(type solid)
			)
			(layer "F.SilkS")
		)
		(fp_line
			(start 5.804 -0.5)
			(end 5.799 2.6)
			(stroke
				(width 0.15)
				(type solid)
			)
			(layer "F.SilkS")
		)
		(fp_line
			(start -1.331 -4.01)
			(end 5.828 -4.01)
			(stroke
				(width 0.15)
				(type solid)
			)
			(layer "F.SilkS")
		)
		(fp_line
			(start 0.14 8.58)
			(end 4.24 8.58)
			(stroke
				(width 0.05)
				(type solid)
			)
			(layer "F.CrtYd")
		)
		(fp_line
			(start 4.24 8.58)
			(end 4.24 2.89)
			(stroke
				(width 0.05)
				(type solid)
			)
			(layer "F.CrtYd")
		)
		(fp_line
			(start -1.6 2.89)
			(end 0.14 2.89)
			(stroke
				(width 0.05)
				(type solid)
			)
			(layer "F.CrtYd")
		)
		(fp_line
			(start 0.14 2.89)
			(end 0.14 8.58)
			(stroke
				(width 0.05)
				(type solid)
			)
			(layer "F.CrtYd")
		)
		(fp_line
			(start 4.24 2.89)
			(end 6.1 2.89)
			(stroke
				(width 0.05)
				(type solid)
			)
			(layer "F.CrtYd")
		)
		(fp_line
			(start 6.1 2.89)
			(end 6.1 -4.21)
			(stroke
				(width 0.05)
				(type solid)
			)
			(layer "F.CrtYd")
		)
		(fp_line
			(start -1.6 -4.21)
			(end -1.6 2.89)
			(stroke
				(width 0.05)
				(type solid)
			)
			(layer "F.CrtYd")
		)
		(fp_line
			(start 6.1 -4.21)
			(end -1.6 -4.21)
			(stroke
				(width 0.05)
				(type solid)
			)
			(layer "F.CrtYd")
		)
		(fp_line
			(start 0.494 8.349)
			(end 4.004 8.349)
			(stroke
				(width 0.15)
				(type solid)
			)
			(layer "F.Fab")
		)
		(fp_line
			(start 4.004 8.349)
			(end 3.999 2.6)
			(stroke
				(width 0.15)
				(type solid)
			)
			(layer "F.Fab")
		)
		(fp_line
			(start -1.307 2.6)
			(end -1.307 -4.01)
			(stroke
				(width 0.15)
				(type solid)
			)
			(layer "F.Fab")
		)
		(fp_line
			(start 0.494 2.6)
			(end 0.494 8.349)
			(stroke
				(width 0.15)
				(type solid)
			)
			(layer "F.Fab")
		)
		(fp_line
			(start 0.494 2.6)
			(end -1.307 2.6)
			(stroke
				(width 0.15)
				(type solid)
			)
			(layer "F.Fab")
		)
		(fp_line
			(start 5.799 2.6)
			(end 3.999 2.6)
			(stroke
				(width 0.15)
				(type solid)
			)
			(layer "F.Fab")
		)
		(fp_line
			(start -1.307 -4.01)
			(end 5.804 -4.01)
			(stroke
				(width 0.15)
				(type solid)
			)
			(layer "F.Fab")
		)
		(fp_line
			(start 5.804 -4.01)
			(end 5.804 2.6)
			(stroke
				(width 0.15)
				(type solid)
			)
			(layer "F.Fab")
		)
		(pad "1" thru_hole circle
			(at 0 0 270)
			(size 1.498 1.498)
			(drill 0.99)
			(layers "*.Cu" "*.Mask")
			(remove_unused_layers no)
			(net 84 "/Com Express 7 MGMT/PWRBTN")
			(pinfunction "1")
			(pintype "passive")
			(teardrops
				(best_length_ratio 0.4)
				(max_length 1)
				(best_width_ratio 0.9)
				(max_width 2)
				(curved_edges yes)
				(filter_ratio 0.9)
				(enabled yes)
				(allow_two_segments yes)
				(prefer_zone_connections yes)
			)
		)
		(pad "2" thru_hole circle
			(at 4.498 0 270)
			(size 1.498 1.498)
			(drill 0.99)
			(layers "*.Cu" "*.Mask")
			(remove_unused_layers no)
			(net 1 "GND")
			(pinfunction "2")
			(pintype "passive")
			(teardrops
				(best_length_ratio 0.4)
				(max_length 1)
				(best_width_ratio 0.9)
				(max_width 2)
				(curved_edges yes)
				(filter_ratio 0.9)
				(enabled yes)
				(allow_two_segments yes)
				(prefer_zone_connections yes)
			)
		)
		(pad "SH" thru_hole circle
			(at -1.256 -2.492 270)
			(size 1.95 1.95)
			(drill 1.3)
			(layers "*.Cu" "*.Mask")
			(remove_unused_layers no)
			(net 1 "GND")
			(pinfunction "SH")
			(pintype "passive")
			(teardrops
				(best_length_ratio 0.4)
				(max_length 1)
				(best_width_ratio 0.9)
				(max_width 2)
				(curved_edges yes)
				(filter_ratio 0.9)
				(enabled yes)
				(allow_two_segments yes)
				(prefer_zone_connections yes)
			)
		)
		(pad "SH" thru_hole circle
			(at 5.754 -2.492 270)
			(size 1.95 1.95)
			(drill 1.3)
			(layers "*.Cu" "*.Mask")
			(remove_unused_layers no)
			(net 1 "GND")
			(pinfunction "SH")
			(pintype "passive")
			(teardrops
				(best_length_ratio 0.4)
				(max_length 1)
				(best_width_ratio 0.9)
				(max_width 2)
				(curved_edges yes)
				(filter_ratio 0.9)
				(enabled yes)
				(allow_two_segments yes)
				(prefer_zone_connections yes)
			)
		)
	)
	(footprint "antmicro-footprints:R_0402_1005Metric"
		(layer "F.Cu")
		(at 163.1 159.36 180)
		(descr "Resistor SMD 0402")
		(tags "resistor SMD 0402")
		(property "Reference" "R32"
			(at -0.8 -0.44 0)
			(layer "F.SilkS")
			(effects
				(font
					(size 0.7 0.7)
					(thickness 0.15)
				)
				(justify left bottom)
			)
		)
		(property "Value" "R_0R_0402"
			(at -1.011843 1.772047 0)
			(layer "F.Fab")
			(effects
				(font
					(size 0.7 0.7)
					(thickness 0.15)
				)
				(justify right bottom)
			)
		)
		(property "Datasheet" "https://industrial.panasonic.com/cdbs/www-data/pdf/RDA0000/AOA0000C301.pdf"
			(at 0 0 180)
			(layer "F.Fab")
			(hide yes)
			(effects
				(font
					(size 1.27 1.27)
					(thickness 0.15)
				)
			)
		)
		(property "Author" "Antmicro"
			(at 326.2 318.72 0)
			(layer "F.Fab")
			(hide yes)
			(effects
				(font
					(size 1 1)
					(thickness 0.15)
				)
			)
		)
		(property "Current" "1A"
			(at 326.2 318.72 0)
			(layer "F.Fab")
			(hide yes)
			(effects
				(font
					(size 1 1)
					(thickness 0.15)
				)
			)
		)
		(property "License" "Apache-2.0"
			(at 326.2 318.72 0)
			(layer "F.Fab")
			(hide yes)
			(effects
				(font
					(size 1 1)
					(thickness 0.15)
				)
			)
		)
		(property "MPN" "ERJ2GE0R00X"
			(at 326.2 318.72 0)
			(layer "F.Fab")
			(hide yes)
			(effects
				(font
					(size 1 1)
					(thickness 0.15)
				)
			)
		)
		(property "Manufacturer" "Panasonic"
			(at 326.2 318.72 0)
			(layer "F.Fab")
			(hide yes)
			(effects
				(font
					(size 1 1)
					(thickness 0.15)
				)
			)
		)
		(property "Public" "False"
			(at 326.2 318.72 0)
			(layer "F.Fab")
			(hide yes)
			(effects
				(font
					(size 1 1)
					(thickness 0.15)
				)
			)
		)
		(property "Tolerance" ""
			(at 326.2 318.72 0)
			(layer "F.Fab")
			(hide yes)
			(effects
				(font
					(size 1 1)
					(thickness 0.15)
				)
			)
		)
		(property "Val" "0R"
			(at 326.2 318.72 0)
			(layer "F.Fab")
			(hide yes)
			(effects
				(font
					(size 1 1)
					(thickness 0.15)
				)
			)
		)
		(sheetname "2xSFP+")
		(sheetfile "2xSFP+.kicad_sch")
		(attr smd dnp)
		(fp_rect
			(start -0.925 -0.47)
			(end 0.925 0.47)
			(stroke
				(width 0.05)
				(type default)
			)
			(fill no)
			(layer "F.CrtYd")
		)
		(fp_rect
			(start -0.5 -0.25)
			(end 0.5 0.25)
			(stroke
				(width 0.15)
				(type solid)
			)
			(fill no)
			(layer "F.Fab")
		)
		(pad "1" smd roundrect
			(at -0.48 0 180)
			(size 0.59 0.64)
			(layers "F.Cu" "F.Mask" "F.Paste")
			(roundrect_rratio 0.25)
			(net 1 "GND")
			(pintype "passive")
			(teardrops
				(best_length_ratio 0.2)
				(max_length 1)
				(best_width_ratio 0.9)
				(max_width 2)
				(curved_edges yes)
				(filter_ratio 0.9)
				(enabled yes)
				(allow_two_segments yes)
				(prefer_zone_connections yes)
			)
		)
		(pad "2" smd roundrect
			(at 0.48 0 180)
			(size 0.59 0.64)
			(layers "F.Cu" "F.Mask" "F.Paste")
			(roundrect_rratio 0.25)
			(net 557 "Net-(U5-A0)")
			(pintype "passive")
			(teardrops
				(best_length_ratio 0.2)
				(max_length 1)
				(best_width_ratio 0.9)
				(max_width 2)
				(curved_edges yes)
				(filter_ratio 0.9)
				(enabled yes)
				(allow_two_segments yes)
				(prefer_zone_connections yes)
			)
		)
	)
	(footprint "antmicro-footprints:Oscillator_SMD_Epson_SG3225EEN_3.2x2.5x1.2mm"
		(layer "F.Cu")
		(at 141.95 138.01 -90)
		(property "Reference" "Y2"
			(at 2.4 -0.55 0)
			(unlocked yes)
			(layer "F.SilkS")
			(effects
				(font
					(size 0.7 0.7)
					(thickness 0.15)
				)
				(justify left bottom)
			)
		)
		(property "Value" "Oscillator_156.25MHz_SG3225EEN"
			(at 0 3 270)
			(unlocked yes)
			(layer "F.Fab")
			(effects
				(font
					(size 0.7 0.7)
					(thickness 0.15)
				)
				(justify left bottom)
			)
		)
		(property "Datasheet" "https://support.epson.biz/td/api/doc_check.php?dl=brief_SG3225EEN&lang=en"
			(at 0 0 270)
			(layer "F.Fab")
			(hide yes)
			(effects
				(font
					(size 1.27 1.27)
					(thickness 0.15)
				)
			)
		)
		(property "Author" "Antmicro"
			(at 3.94 279.96 0)
			(layer "F.Fab")
			(hide yes)
			(effects
				(font
					(size 1 1)
					(thickness 0.15)
				)
			)
		)
		(property "License" "Apache-2.0"
			(at 3.94 279.96 0)
			(layer "F.Fab")
			(hide yes)
			(effects
				(font
					(size 1 1)
					(thickness 0.15)
				)
			)
		)
		(property "MPN" "SG3225EEN_156.250000M-CDGA3"
			(at 3.94 279.96 0)
			(layer "F.Fab")
			(hide yes)
			(effects
				(font
					(size 1 1)
					(thickness 0.15)
				)
			)
		)
		(property "Manufacturer" "Epson"
			(at 3.94 279.96 0)
			(layer "F.Fab")
			(hide yes)
			(effects
				(font
					(size 1 1)
					(thickness 0.15)
				)
			)
		)
		(property "Public" "False"
			(at 3.94 279.96 0)
			(layer "F.Fab")
			(hide yes)
			(effects
				(font
					(size 1 1)
					(thickness 0.15)
				)
			)
		)
		(property "Val" "156.25MHz"
			(at 3.94 279.96 0)
			(layer "F.Fab")
			(hide yes)
			(effects
				(font
					(size 1 1)
					(thickness 0.15)
				)
			)
		)
		(sheetname "KR to SFI #1")
		(sheetfile "kr_sfi.kicad_sch")
		(attr smd)
		(fp_line
			(start 1.25 1.925)
			(end -1.25 1.925)
			(stroke
				(width 0.15)
				(type solid)
			)
			(layer "F.SilkS")
		)
		(fp_line
			(start 1.25 -1.825)
			(end -1.25 -1.825)
			(stroke
				(width 0.15)
				(type solid)
			)
			(layer "F.SilkS")
		)
		(fp_circle
			(center -1.57 -1.87)
			(end -1.57 -1.82)
			(stroke
				(width 0.15)
				(type solid)
			)
			(fill yes)
			(layer "F.SilkS")
		)
		(fp_rect
			(start 1.58 -1.85)
			(end -1.6 1.96)
			(stroke
				(width 0.05)
				(type solid)
			)
			(fill no)
			(layer "F.CrtYd")
		)
		(pad "1" smd rect
			(at -0.925 -1.24 180)
			(size 0.92 1.05)
			(layers "F.Cu" "F.Mask" "F.Paste")
			(net 647 "Net-(Y2-EN)")
			(pinfunction "EN")
			(pintype "input")
			(solder_mask_margin 0.05)
			(teardrops
				(best_length_ratio 0.2)
				(max_length 1)
				(best_width_ratio 0.9)
				(max_width 2)
				(curved_edges yes)
				(filter_ratio 0.9)
				(enabled yes)
				(allow_two_segments yes)
				(prefer_zone_connections yes)
			)
		)
		(pad "2" smd rect
			(at -0.925 0.05 180)
			(size 0.8 1.05)
			(layers "F.Cu" "F.Mask" "F.Paste")
			(net 864 "unconnected-(Y2-NC-Pad2)")
			(pinfunction "NC")
			(pintype "no_connect")
			(solder_mask_margin 0.05)
			(teardrops
				(best_length_ratio 0.2)
				(max_length 1)
				(best_width_ratio 0.9)
				(max_width 2)
				(curved_edges yes)
				(filter_ratio 0.9)
				(enabled yes)
				(allow_two_segments yes)
				(prefer_zone_connections yes)
			)
		)
		(pad "3" smd rect
			(at -0.925 1.34 180)
			(size 0.92 1.05)
			(layers "F.Cu" "F.Mask" "F.Paste")
			(net 1 "GND")
			(pinfunction "GND")
			(pintype "power_in")
			(solder_mask_margin 0.05)
			(teardrops
				(best_length_ratio 0.2)
				(max_length 1)
				(best_width_ratio 0.9)
				(max_width 2)
				(curved_edges yes)
				(filter_ratio 0.9)
				(enabled yes)
				(allow_two_segments yes)
				(prefer_zone_connections yes)
			)
		)
		(pad "4" smd rect
			(at 0.925 1.34 180)
			(size 0.92 1.05)
			(layers "F.Cu" "F.Mask" "F.Paste")
			(net 107 "/2xSFP+/KR to SFI #1/CLK+")
			(pinfunction "OUT+")
			(pintype "output")
			(solder_mask_margin 0.05)
			(teardrops
				(best_length_ratio 0.2)
				(max_length 1)
				(best_width_ratio 0.9)
				(max_width 2)
				(curved_edges yes)
				(filter_ratio 0.9)
				(enabled yes)
				(allow_two_segments yes)
				(prefer_zone_connections yes)
			)
		)
		(pad "5" smd rect
			(at 0.925 0.05 180)
			(size 0.8 1.05)
			(layers "F.Cu" "F.Mask" "F.Paste")
			(net 109 "/2xSFP+/KR to SFI #1/CLK-")
			(pinfunction "OUT-")
			(pintype "output")
			(solder_mask_margin 0.05)
			(teardrops
				(best_length_ratio 0.2)
				(max_length 1)
				(best_width_ratio 0.9)
				(max_width 2)
				(curved_edges yes)
				(filter_ratio 0.9)
				(enabled yes)
				(allow_two_segments yes)
				(prefer_zone_connections yes)
			)
		)
		(pad "6" smd rect
			(at 0.925 -1.24 180)
			(size 0.92 1.05)
			(layers "F.Cu" "F.Mask" "F.Paste")
			(net 2 "+3V3")
			(pinfunction "VCC")
			(pintype "power_in")
			(solder_mask_margin 0.05)
			(teardrops
				(best_length_ratio 0.2)
				(max_length 1)
				(best_width_ratio 0.9)
				(max_width 2)
				(curved_edges yes)
				(filter_ratio 0.9)
				(enabled yes)
				(allow_two_segments yes)
				(prefer_zone_connections yes)
			)
		)
	)
	(footprint "antmicro-footprints:TP_SMD_0.75mm"
		(layer "F.Cu")
		(at 137.54 128.71)
		(property "Reference" "TP92"
			(at 0.51 -3.3 90)
			(layer "F.SilkS")
			(effects
				(font
					(size 0.7 0.7)
					(thickness 0.15)
				)
				(justify left bottom)
			)
		)
		(property "Value" "TP_0.75mm_SMD"
			(at 0 1.2 0)
			(layer "F.Fab")
			(effects
				(font
					(size 0.7 0.7)
					(thickness 0.15)
				)
				(justify left bottom)
			)
		)
		(property "Author" "Antmicro"
			(at 0 0 0)
			(layer "F.Fab")
			(hide yes)
			(effects
				(font
					(size 1 1)
					(thickness 0.15)
				)
			)
		)
		(property "License" "Apache-2.0"
			(at 0 0 0)
			(layer "F.Fab")
			(hide yes)
			(effects
				(font
					(size 1 1)
					(thickness 0.15)
				)
			)
		)
		(property "MPN" ""
			(at 0 0 0)
			(layer "F.Fab")
			(hide yes)
			(effects
				(font
					(size 1 1)
					(thickness 0.15)
				)
			)
		)
		(property "Manufacturer" ""
			(at 0 0 0)
			(layer "F.Fab")
			(hide yes)
			(effects
				(font
					(size 1 1)
					(thickness 0.15)
				)
			)
		)
		(property "Public" "False"
			(at 0 0 0)
			(layer "F.Fab")
			(hide yes)
			(effects
				(font
					(size 1 1)
					(thickness 0.15)
				)
			)
		)
		(sheetname "KR to SFI #2")
		(sheetfile "kr_sfi.kicad_sch")
		(attr exclude_from_pos_files exclude_from_bom)
		(fp_circle
			(center 0 0)
			(end 0.475 0)
			(stroke
				(width 0.05)
				(type default)
			)
			(fill no)
			(layer "F.CrtYd")
		)
		(pad "1" smd circle
			(at 0 0)
			(size 0.75 0.75)
			(layers "F.Cu" "F.Mask")
			(net 755 "Net-(U45A-LS_OK_{IN_A})")
			(pinfunction "1")
			(pintype "passive")
			(teardrops
				(best_length_ratio 0.4)
				(max_length 1)
				(best_width_ratio 0.9)
				(max_width 2)
				(curved_edges yes)
				(filter_ratio 0.9)
				(enabled yes)
				(allow_two_segments yes)
				(prefer_zone_connections yes)
			)
		)
	)
	(footprint "antmicro-footprints:R_0402_1005Metric"
		(layer "F.Cu")
		(at 113.4 144.36 90)
		(descr "Resistor SMD 0402")
		(tags "resistor SMD 0402")
		(property "Reference" "R213"
			(at 0.8 0.4 90)
			(layer "F.SilkS")
			(effects
				(font
					(size 0.7 0.7)
					(thickness 0.15)
				)
				(justify left bottom)
			)
		)
		(property "Value" "R_1k_0402"
			(at -1.011843 1.772047 90)
			(layer "F.Fab")
			(effects
				(font
					(size 0.7 0.7)
					(thickness 0.15)
				)
				(justify left bottom)
			)
		)
		(property "Datasheet" "https://www.bourns.com/docs/product-datasheets/cr.pdf"
			(at 0 0 90)
			(layer "F.Fab")
			(hide yes)
			(effects
				(font
					(size 1.27 1.27)
					(thickness 0.15)
				)
			)
		)
		(property "Author" "Antmicro"
			(at 257.76 30.96 0)
			(layer "F.Fab")
			(hide yes)
			(effects
				(font
					(size 1 1)
					(thickness 0.15)
				)
			)
		)
		(property "License" "Apache-2.0"
			(at 257.76 30.96 0)
			(layer "F.Fab")
			(hide yes)
			(effects
				(font
					(size 1 1)
					(thickness 0.15)
				)
			)
		)
		(property "MPN" "CR0402-FX-1001GLF"
			(at 257.76 30.96 0)
			(layer "F.Fab")
			(hide yes)
			(effects
				(font
					(size 1 1)
					(thickness 0.15)
				)
			)
		)
		(property "Manufacturer" "Bourns"
			(at 257.76 30.96 0)
			(layer "F.Fab")
			(hide yes)
			(effects
				(font
					(size 1 1)
					(thickness 0.15)
				)
			)
		)
		(property "Public" "False"
			(at 257.76 30.96 0)
			(layer "F.Fab")
			(hide yes)
			(effects
				(font
					(size 1 1)
					(thickness 0.15)
				)
			)
		)
		(property "Tolerance" "1%"
			(at 257.76 30.96 0)
			(layer "F.Fab")
			(hide yes)
			(effects
				(font
					(size 1 1)
					(thickness 0.15)
				)
			)
		)
		(property "Val" "1k"
			(at 257.76 30.96 0)
			(layer "F.Fab")
			(hide yes)
			(effects
				(font
					(size 1 1)
					(thickness 0.15)
				)
			)
		)
		(sheetname "PCIe redriver")
		(sheetfile "pcie_redriver.kicad_sch")
		(attr smd dnp)
		(fp_rect
			(start -0.925 -0.47)
			(end 0.925 0.47)
			(stroke
				(width 0.05)
				(type default)
			)
			(fill no)
			(layer "F.CrtYd")
		)
		(fp_rect
			(start -0.5 -0.25)
			(end 0.5 0.25)
			(stroke
				(width 0.15)
				(type solid)
			)
			(fill no)
			(layer "F.Fab")
		)
		(pad "1" smd roundrect
			(at -0.48 0 90)
			(size 0.59 0.64)
			(layers "F.Cu" "F.Mask" "F.Paste")
			(roundrect_rratio 0.25)
			(net 1 "GND")
			(pintype "passive")
			(teardrops
				(best_length_ratio 0.2)
				(max_length 1)
				(best_width_ratio 0.9)
				(max_width 2)
				(curved_edges yes)
				(filter_ratio 0.9)
				(enabled yes)
				(allow_two_segments yes)
				(prefer_zone_connections yes)
			)
		)
		(pad "2" smd roundrect
			(at 0.48 0 90)
			(size 0.59 0.64)
			(layers "F.Cu" "F.Mask" "F.Paste")
			(roundrect_rratio 0.25)
			(net 628 "/PCIe redriver/TX_SW")
			(pintype "passive")
			(teardrops
				(best_length_ratio 0.2)
				(max_length 1)
				(best_width_ratio 0.9)
				(max_width 2)
				(curved_edges yes)
				(filter_ratio 0.9)
				(enabled yes)
				(allow_two_segments yes)
				(prefer_zone_connections yes)
			)
		)
	)
)
